#ISCELL
  mstr_misc prelim *
  *
#ISCELL
  mstr_symbols design_note *
  *
#ISCELL
  mstr_symbols intel_corp_bpage *
  *
#ISCELL
  mstr_standard offpage *
  page33_i1
#ISCELL
  mstr_standard tap *
  page33_i10
#ISCELL
  mstr_standard tap *
  page33_i11
#ISCELL
  mstr_standard tap *
  page33_i13
#ISCELL
  mstr_standard tap *
  page33_i14
#ISCELL
  mstr_standard tap *
  page33_i15
#ISCELL
  mstr_standard tap *
  page33_i16
#ISCELL
  mstr_standard tap *
  page33_i17
#ISCELL
  mstr_standard tap *
  page33_i18
#ISCELL
  mstr_standard tap *
  page33_i19
#ISCELL
  mstr_standard offpage *
  page33_i2
#ISCELL
  mstr_standard tap *
  page33_i20
#ISCELL
  mstr_standard tap *
  page33_i21
#ISCELL
  mstr_standard tap *
  page33_i22
#ISCELL
  mstr_standard tap *
  page33_i23
#ISCELL
  mstr_standard tap *
  page33_i24
#ISCELL
  mstr_standard tap *
  page33_i25
#ISCELL
  mstr_standard tap *
  page33_i26
#ISCELL
  mstr_standard tap *
  page33_i27
#ISCELL
  mstr_standard tap *
  page33_i28
#ISCELL
  mstr_standard tap *
  page33_i29
#ISCELL
  mstr_standard tap *
  page33_i3
#ISCELL
  mstr_standard tap *
  page33_i30
#ISCELL
  mstr_standard tap *
  page33_i31
#ISCELL
  mstr_standard tap *
  page33_i32
#ISCELL
  mstr_standard tap *
  page33_i33
#ISCELL
  mstr_standard tap *
  page33_i34
#ISCELL
  mstr_standard tap *
  page33_i35
#ISCELL
  mstr_standard tap *
  page33_i36
#ISCELL
  mstr_standard tap *
  page33_i37
#ISCELL
  mstr_standard tap *
  page33_i38
#ISCELL
  mstr_standard tap *
  page33_i39
#ISCELL
  mstr_standard tap *
  page33_i4
#ISCELL
  mstr_standard tap *
  page33_i40
#ISCELL
  mstr_standard tap *
  page33_i41
#ISCELL
  mstr_standard tap *
  page33_i42
#ISCELL
  mstr_standard tap *
  page33_i43
#ISCELL
  mstr_standard tap *
  page33_i44
#ISCELL
  mstr_standard tap *
  page33_i45
#ISCELL
  mstr_standard tap *
  page33_i46
#ISCELL
  mstr_standard tap *
  page33_i47
#ISCELL
  mstr_standard tap *
  page33_i48
#ISCELL
  mstr_standard tap *
  page33_i49
#ISCELL
  mstr_standard tap *
  page33_i5
#ISCELL
  mstr_standard tap *
  page33_i50
#ISCELL
  mstr_standard tap *
  page33_i51
#ISCELL
  mstr_standard tap *
  page33_i52
#ISCELL
  mstr_standard tap *
  page33_i53
#ISCELL
  mstr_standard tap *
  page33_i54
#ISCELL
  mstr_standard tap *
  page33_i55
#ISCELL
  mstr_standard tap *
  page33_i56
#ISCELL
  mstr_standard tap *
  page33_i57
#ISCELL
  mstr_standard tap *
  page33_i58
#ISCELL
  mstr_standard tap *
  page33_i59
#ISCELL
  mstr_standard tap *
  page33_i6
#ISCELL
  mstr_standard tap *
  page33_i60
#ISCELL
  mstr_standard tap *
  page33_i61
#ISCELL
  mstr_standard tap *
  page33_i62
#ISCELL
  mstr_standard tap *
  page33_i63
#ISCELL
  mstr_standard tap *
  page33_i64
#ISCELL
  mstr_standard tap *
  page33_i65
#ISCELL
  mstr_standard tap *
  page33_i66
#ISCELL
  mstr_standard tap *
  page33_i67
#ISCELL
  mstr_standard tap *
  page33_i68
#ISCELL
  mstr_standard tap *
  page33_i69
#ISCELL
  mstr_standard tap *
  page33_i7
#ISCELL
  mstr_standard tap *
  page33_i70
#ISCELL
  mstr_standard tap *
  page33_i71
#ISCELL
  mstr_standard tap *
  page33_i72
#ISCELL
  mstr_standard tap *
  page33_i73
#ISCELL
  mstr_standard tap *
  page33_i74
#ISCELL
  mstr_standard tap *
  page33_i75
#ISCELL
  mstr_standard tap *
  page33_i76
#ISCELL
  mstr_standard tap *
  page33_i77
#ISCELL
  mstr_standard tap *
  page33_i78
#ISCELL
  mstr_standard tap *
  page33_i79
#ISCELL
  mstr_standard tap *
  page33_i8
#ISCELL
  mstr_standard tap *
  page33_i80
#ISCELL
  mstr_standard tap *
  page33_i81
#ISCELL
  mstr_standard tap *
  page33_i82
#ISCELL
  mstr_standard tap *
  page33_i83
#ISCELL
  mstr_standard offpage *
  page33_i84
#ISCELL
  mstr_standard offpage *
  page33_i85
#CELL
  chpset_lib skx_ext_b *
  page33_i86
#ISCELL
  mstr_standard tap *
  page33_i9
